(kicad_pcb
	(version 20260206)
	(generator "pcbnew")
	(generator_version "10.0")
	(general
		(thickness 1.6)
		(legacy_teardrops no)
	)
	(paper "A4")
	(title_block
		(title "04192023_DAF0TMB3IC0_F0TG_MB_C_brd_V02_OCP.brd")
		(comment 1 "Grand Teton / footprint 2783 of 8354 (U26), pads 3228-3336 of 6102")
	)
	(layers
		(0 "F.Cu" signal "TOP")
		(4 "In1.Cu" signal "GND")
		(6 "In2.Cu" signal "IN1")
		(8 "In3.Cu" signal "GND1")
		(10 "In4.Cu" signal "IN2")
		(12 "In5.Cu" signal "GND2")
		(14 "In6.Cu" signal "IN3")
		(16 "In7.Cu" signal "GND3")
		(18 "In8.Cu" signal "VCC")
		(20 "In9.Cu" signal "VCC1")
		(22 "In10.Cu" signal "GND4")
		(24 "In11.Cu" signal "IN4")
		(26 "In12.Cu" signal "GND5")
		(28 "In13.Cu" signal "IN5")
		(30 "In14.Cu" signal "GND6")
		(32 "In15.Cu" signal "IN6")
		(34 "In16.Cu" signal "GND7")
		(2 "B.Cu" signal "BOTTOM")
		(9 "F.Adhes" user "F.Adhesive")
		(11 "B.Adhes" user "B.Adhesive")
		(13 "F.Paste" user "Package Geometry/Pastemask Top")
		(15 "B.Paste" user "Package Geometry/Pastemask Bottom")
		(5 "F.SilkS" user "Ref Des/Silkscreen Top")
		(7 "B.SilkS" user "Ref Des/Silkscreen Bottom")
		(1 "F.Mask" user "Board Geometry/Soldermask Top")
		(3 "B.Mask" user "Board Geometry/Soldermask Bottom")
		(17 "Dwgs.User" user "User.Drawings")
		(19 "Cmts.User" user "User.Comments")
		(21 "Eco1.User" user "User.Eco1")
		(23 "Eco2.User" user "User.Eco2")
		(25 "Edge.Cuts" user "Board Geometry/Outline")
		(27 "Margin" user)
		(31 "F.CrtYd" user "Package Geometry/Place Bound Top")
		(29 "B.CrtYd" user "Package Geometry/Place Bound Bottom")
		(35 "F.Fab" user "Ref Des/Assembly Top")
		(33 "B.Fab" user "Ref Des/Assembly Bottom")
	)
	(footprint ""
		(layer "F.Cu")
		(at 111.927894 -258.880356 180)
		(property "Reference" "U26"
			(at -45.05579 -61.794136 0)
			(unlocked yes)
			(layer "F.SilkS")
			(effects
				(font
					(size 0.7874 0.5842)
					(thickness 0.1524)
				)
			)
		)
		(property "Value" ""
			(at 0 0 180)
			(layer "F.Fab")
			(effects
				(font
					(size 1.27 1.27)
				)
			)
		)
		(duplicate_pad_numbers_are_jumpers no)
		(pad "CF62" smd circle
			(at 22.409912 18.18005 180)
			(size 0.450088 0.450088)
			(layers "F.Cu" "F.Mask" "F.Paste")
			(net "M_B_CPU1_SB_DQS_DP<5>")
		)
		(pad "CF63" smd circle
			(at 23.349966 18.18005 180)
			(size 0.450088 0.450088)
			(layers "F.Cu" "F.Mask" "F.Paste")
			(net "M_B_CPU1_SB_DQ<4>")
		)
		(pad "CF64" smd circle
			(at 24.29002 18.18005 180)
			(size 0.450088 0.450088)
			(layers "F.Cu" "F.Mask" "F.Paste")
			(net "GND")
		)
		(pad "CF65" smd circle
			(at 25.230074 18.18005 180)
			(size 0.450088 0.450088)
			(layers "F.Cu" "F.Mask" "F.Paste")
			(net "M_F_CPU1_SB_DQS_DP<5>")
		)
		(pad "CF66" smd circle
			(at 26.170128 18.18005 180)
			(size 0.450088 0.450088)
			(layers "F.Cu" "F.Mask" "F.Paste")
			(net "GND")
		)
		(pad "CF67" smd circle
			(at 27.109928 18.18005 180)
			(size 0.450088 0.450088)
			(layers "F.Cu" "F.Mask" "F.Paste")
			(net "M_F_CPU1_SB_DQ<4>")
		)
		(pad "CF68" smd circle
			(at 28.049982 18.18005 180)
			(size 0.450088 0.450088)
			(layers "F.Cu" "F.Mask" "F.Paste")
			(net "GND")
		)
		(pad "CF69" smd circle
			(at 28.990036 18.18005 180)
			(size 0.450088 0.450088)
			(layers "F.Cu" "F.Mask" "F.Paste")
			(net "M_E_CPU1_SB_DQS_DP<5>")
		)
		(pad "CF70" smd circle
			(at 29.93009 18.18005 180)
			(size 0.450088 0.450088)
			(layers "F.Cu" "F.Mask" "F.Paste")
			(net "M_E_CPU1_SB_DQ<4>")
		)
		(pad "CF71" smd circle
			(at 30.86989 18.18005 180)
			(size 0.450088 0.450088)
			(layers "F.Cu" "F.Mask" "F.Paste")
			(net "GND")
		)
		(pad "CF72" smd circle
			(at 31.809944 18.18005 180)
			(size 0.450088 0.450088)
			(layers "F.Cu" "F.Mask" "F.Paste")
			(net "M_A_CPU1_SB_DQS_DP<5>")
		)
		(pad "CF73" smd circle
			(at 32.749998 18.18005 180)
			(size 0.450088 0.450088)
			(layers "F.Cu" "F.Mask" "F.Paste")
			(net "GND")
		)
		(pad "CF74" smd circle
			(at 33.690052 18.18005 180)
			(size 0.450088 0.450088)
			(layers "F.Cu" "F.Mask" "F.Paste")
			(net "M_A_CPU1_SB_DQ<4>")
		)
		(pad "CG1" smd circle
			(at -34.459926 18.990056 180)
			(size 0.450088 0.450088)
			(layers "F.Cu" "F.Mask" "F.Paste")
			(net "GND")
		)
		(pad "CG2" smd circle
			(at -33.519872 18.990056 180)
			(size 0.450088 0.450088)
			(layers "F.Cu" "F.Mask" "F.Paste")
			(net "M_G_CPU1_SB_DQ<6>")
		)
		(pad "CG3" smd circle
			(at -32.580072 18.990056 180)
			(size 0.450088 0.450088)
			(layers "F.Cu" "F.Mask" "F.Paste")
			(net "M_G_CPU1_SB_DQ<5>")
		)
		(pad "CG4" smd circle
			(at -31.640018 18.990056 180)
			(size 0.450088 0.450088)
			(layers "F.Cu" "F.Mask" "F.Paste")
			(net "PVDD11_S3_P1")
		)
		(pad "CG5" smd circle
			(at -30.699964 18.990056 180)
			(size 0.450088 0.450088)
			(layers "F.Cu" "F.Mask" "F.Paste")
			(net "M_K_CPU1_SB_DQ<6>")
		)
		(pad "CG6" smd circle
			(at -29.75991 18.990056 180)
			(size 0.450088 0.450088)
			(layers "F.Cu" "F.Mask" "F.Paste")
			(net "GND")
		)
		(pad "CG7" smd circle
			(at -28.82011 18.990056 180)
			(size 0.450088 0.450088)
			(layers "F.Cu" "F.Mask" "F.Paste")
			(net "M_K_CPU1_SB_DQ<5>")
		)
		(pad "CG8" smd circle
			(at -27.880056 18.990056 180)
			(size 0.450088 0.450088)
			(layers "F.Cu" "F.Mask" "F.Paste")
			(net "GND")
		)
		(pad "CG9" smd circle
			(at -26.940002 18.990056 180)
			(size 0.450088 0.450088)
			(layers "F.Cu" "F.Mask" "F.Paste")
			(net "M_L_CPU1_SB_DQ<6>")
		)
		(pad "CG10" smd circle
			(at -25.999948 18.990056 180)
			(size 0.450088 0.450088)
			(layers "F.Cu" "F.Mask" "F.Paste")
			(net "M_L_CPU1_SB_DQ<5>")
		)
		(pad "CG11" smd circle
			(at -25.059894 18.990056 180)
			(size 0.450088 0.450088)
			(layers "F.Cu" "F.Mask" "F.Paste")
			(net "PVDD11_S3_P1")
		)
		(pad "CG12" smd circle
			(at -24.120094 18.990056 180)
			(size 0.450088 0.450088)
			(layers "F.Cu" "F.Mask" "F.Paste")
			(net "M_H_CPU1_SB_DQ<6>")
		)
		(pad "CG13" smd circle
			(at -23.18004 18.990056 180)
			(size 0.450088 0.450088)
			(layers "F.Cu" "F.Mask" "F.Paste")
			(net "GND")
		)
		(pad "CG14" smd circle
			(at -22.239986 18.990056 180)
			(size 0.450088 0.450088)
			(layers "F.Cu" "F.Mask" "F.Paste")
			(net "M_H_CPU1_SB_DQ<5>")
		)
		(pad "CG15" smd circle
			(at -21.299932 18.990056 180)
			(size 0.450088 0.450088)
			(layers "F.Cu" "F.Mask" "F.Paste")
			(net "GND")
		)
		(pad "CG16" smd circle
			(at -20.359878 18.990056 180)
			(size 0.450088 0.450088)
			(layers "F.Cu" "F.Mask" "F.Paste")
			(net "M_J_CPU1_SB_DQ<6>")
		)
		(pad "CG17" smd circle
			(at -19.420078 18.990056 180)
			(size 0.450088 0.450088)
			(layers "F.Cu" "F.Mask" "F.Paste")
			(net "M_J_CPU1_SB_DQ<5>")
		)
		(pad "CG18" smd circle
			(at -18.480024 18.990056 180)
			(size 0.450088 0.450088)
			(layers "F.Cu" "F.Mask" "F.Paste")
			(net "PVDD11_S3_P1")
		)
		(pad "CG19" smd circle
			(at -17.53997 18.990056 180)
			(size 0.450088 0.450088)
			(layers "F.Cu" "F.Mask" "F.Paste")
			(net "M_I_CPU1_SB_DQ<6>")
		)
		(pad "CG20" smd circle
			(at -16.599916 18.990056 180)
			(size 0.450088 0.450088)
			(layers "F.Cu" "F.Mask" "F.Paste")
			(net "GND")
		)
		(pad "CG21" smd circle
			(at -15.660116 18.990056 180)
			(size 0.450088 0.450088)
			(layers "F.Cu" "F.Mask" "F.Paste")
			(net "M_I_CPU1_SB_DQ<5>")
		)
		(pad "CG22" smd circle
			(at -14.720062 18.990056 180)
			(size 0.450088 0.450088)
			(layers "F.Cu" "F.Mask" "F.Paste")
			(net "GND")
		)
		(pad "CG23" smd circle
			(at -13.780008 18.990056 180)
			(size 0.450088 0.450088)
			(layers "F.Cu" "F.Mask" "F.Paste")
			(net "P5E_CPU1_P3_TX_DN<14>")
		)
		(pad "CG24" smd circle
			(at -12.839954 18.990056 180)
			(size 0.450088 0.450088)
			(layers "F.Cu" "F.Mask" "F.Paste")
			(net "P5E_CPU1_P3_TX_DP<14>")
		)
		(pad "CG25" smd circle
			(at -11.8999 18.990056 180)
			(size 0.450088 0.450088)
			(layers "F.Cu" "F.Mask" "F.Paste")
			(net "GND")
		)
		(pad "CG26" smd circle
			(at -10.9601 18.990056 180)
			(size 0.450088 0.450088)
			(layers "F.Cu" "F.Mask" "F.Paste")
			(net "P5E_CPU1_P3_TX_DN<11>")
		)
		(pad "CG27" smd circle
			(at -10.020046 18.990056 180)
			(size 0.450088 0.450088)
			(layers "F.Cu" "F.Mask" "F.Paste")
			(net "P5E_CPU1_P3_TX_DP<11>")
		)
		(pad "CG28" smd circle
			(at -9.079992 18.990056 180)
			(size 0.450088 0.450088)
			(layers "F.Cu" "F.Mask" "F.Paste")
			(net "GND")
		)
		(pad "CG29" smd circle
			(at -8.139938 18.990056 180)
			(size 0.450088 0.450088)
			(layers "F.Cu" "F.Mask" "F.Paste")
			(net "P5E_CPU1_P3_TX_DN<8>")
		)
		(pad "CG30" smd circle
			(at -7.199884 18.990056 180)
			(size 0.450088 0.450088)
			(layers "F.Cu" "F.Mask" "F.Paste")
			(net "P5E_CPU1_P3_TX_DP<8>")
		)
		(pad "CG31" smd circle
			(at -6.260084 18.990056 180)
			(size 0.450088 0.450088)
			(layers "F.Cu" "F.Mask" "F.Paste")
			(net "GND")
		)
		(pad "CG32" smd circle
			(at -5.32003 18.990056 180)
			(size 0.450088 0.450088)
			(layers "F.Cu" "F.Mask" "F.Paste")
			(net "P5E_CPU1_P3_TX_DN<5>")
		)
		(pad "CG33" smd circle
			(at -4.379976 18.990056 180)
			(size 0.450088 0.450088)
			(layers "F.Cu" "F.Mask" "F.Paste")
			(net "P5E_CPU1_P3_TX_DP<5>")
		)
		(pad "CG34" smd circle
			(at -3.439922 18.990056 180)
			(size 0.450088 0.450088)
			(layers "F.Cu" "F.Mask" "F.Paste")
			(net "GND")
		)
		(pad "CG35" smd circle
			(at -2.500122 18.990056 180)
			(size 0.450088 0.450088)
			(layers "F.Cu" "F.Mask" "F.Paste")
			(net "PVDDCR_CPU1_P1")
		)
		(pad "CG36" smd circle
			(at -1.560068 18.990056 180)
			(size 0.450088 0.450088)
			(layers "F.Cu" "F.Mask" "F.Paste")
			(net "PVDDCR_CPU1_P1")
		)
		(pad "CG40" smd circle
			(at 1.260094 18.990056 180)
			(size 0.450088 0.450088)
			(layers "F.Cu" "F.Mask" "F.Paste")
			(net "PVDDCR_CPU1_P1")
		)
		(pad "CG41" smd circle
			(at 2.199894 18.990056 180)
			(size 0.450088 0.450088)
			(layers "F.Cu" "F.Mask" "F.Paste")
			(net "PVDDCR_CPU1_P1")
		)
		(pad "CG42" smd circle
			(at 3.139948 18.990056 180)
			(size 0.450088 0.450088)
			(layers "F.Cu" "F.Mask" "F.Paste")
			(net "GND")
		)
		(pad "CG43" smd circle
			(at 4.080002 18.990056 180)
			(size 0.450088 0.450088)
			(layers "F.Cu" "F.Mask" "F.Paste")
			(net "P5E_CPU1_P1_RX_DP<10>")
		)
		(pad "CG44" smd circle
			(at 5.020056 18.990056 180)
			(size 0.450088 0.450088)
			(layers "F.Cu" "F.Mask" "F.Paste")
			(net "P5E_CPU1_P1_RX_DN<10>")
		)
		(pad "CG45" smd circle
			(at 5.96011 18.990056 180)
			(size 0.450088 0.450088)
			(layers "F.Cu" "F.Mask" "F.Paste")
			(net "GND")
		)
		(pad "CG46" smd circle
			(at 6.89991 18.990056 180)
			(size 0.450088 0.450088)
			(layers "F.Cu" "F.Mask" "F.Paste")
			(net "P5E_CPU1_P1_RX_DP<7>")
		)
		(pad "CG47" smd circle
			(at 7.839964 18.990056 180)
			(size 0.450088 0.450088)
			(layers "F.Cu" "F.Mask" "F.Paste")
			(net "P5E_CPU1_P1_RX_DN<7>")
		)
		(pad "CG48" smd circle
			(at 8.780018 18.990056 180)
			(size 0.450088 0.450088)
			(layers "F.Cu" "F.Mask" "F.Paste")
			(net "GND")
		)
		(pad "CG49" smd circle
			(at 9.720072 18.990056 180)
			(size 0.450088 0.450088)
			(layers "F.Cu" "F.Mask" "F.Paste")
			(net "P5E_CPU1_P1_RX_DP<4>")
		)
		(pad "CG50" smd circle
			(at 10.659872 18.990056 180)
			(size 0.450088 0.450088)
			(layers "F.Cu" "F.Mask" "F.Paste")
			(net "P5E_CPU1_P1_RX_DN<4>")
		)
		(pad "CG51" smd circle
			(at 11.599926 18.990056 180)
			(size 0.450088 0.450088)
			(layers "F.Cu" "F.Mask" "F.Paste")
			(net "GND")
		)
		(pad "CG52" smd circle
			(at 12.53998 18.990056 180)
			(size 0.450088 0.450088)
			(layers "F.Cu" "F.Mask" "F.Paste")
			(net "P5E_CPU1_P1_RX_DP<1>")
		)
		(pad "CG53" smd circle
			(at 13.480034 18.990056 180)
			(size 0.450088 0.450088)
			(layers "F.Cu" "F.Mask" "F.Paste")
			(net "P5E_CPU1_P1_RX_DN<1>")
		)
		(pad "CG54" smd circle
			(at 14.420088 18.990056 180)
			(size 0.450088 0.450088)
			(layers "F.Cu" "F.Mask" "F.Paste")
			(net "GND")
		)
		(pad "CG55" smd circle
			(at 15.359888 18.990056 180)
			(size 0.450088 0.450088)
			(layers "F.Cu" "F.Mask" "F.Paste")
			(net "M_C_CPU1_SB_DQ<5>")
		)
		(pad "CG56" smd circle
			(at 16.299942 18.990056 180)
			(size 0.450088 0.450088)
			(layers "F.Cu" "F.Mask" "F.Paste")
			(net "GND")
		)
		(pad "CG57" smd circle
			(at 17.239996 18.990056 180)
			(size 0.450088 0.450088)
			(layers "F.Cu" "F.Mask" "F.Paste")
			(net "M_C_CPU1_SB_DQ<6>")
		)
		(pad "CG58" smd circle
			(at 18.18005 18.990056 180)
			(size 0.450088 0.450088)
			(layers "F.Cu" "F.Mask" "F.Paste")
			(net "PVDDIO_P1")
		)
		(pad "CG59" smd circle
			(at 19.120104 18.990056 180)
			(size 0.450088 0.450088)
			(layers "F.Cu" "F.Mask" "F.Paste")
			(net "M_D_CPU1_SB_DQ<5>")
		)
		(pad "CG60" smd circle
			(at 20.059904 18.990056 180)
			(size 0.450088 0.450088)
			(layers "F.Cu" "F.Mask" "F.Paste")
			(net "M_D_CPU1_SB_DQ<6>")
		)
		(pad "CG61" smd circle
			(at 20.999958 18.990056 180)
			(size 0.450088 0.450088)
			(layers "F.Cu" "F.Mask" "F.Paste")
			(net "GND")
		)
		(pad "CG62" smd circle
			(at 21.940012 18.990056 180)
			(size 0.450088 0.450088)
			(layers "F.Cu" "F.Mask" "F.Paste")
			(net "M_B_CPU1_SB_DQ<5>")
		)
		(pad "CG63" smd circle
			(at 22.880066 18.990056 180)
			(size 0.450088 0.450088)
			(layers "F.Cu" "F.Mask" "F.Paste")
			(net "GND")
		)
		(pad "CG64" smd circle
			(at 23.82012 18.990056 180)
			(size 0.450088 0.450088)
			(layers "F.Cu" "F.Mask" "F.Paste")
			(net "M_B_CPU1_SB_DQ<6>")
		)
		(pad "CG65" smd circle
			(at 24.75992 18.990056 180)
			(size 0.450088 0.450088)
			(layers "F.Cu" "F.Mask" "F.Paste")
			(net "PVDDIO_P1")
		)
		(pad "CG66" smd circle
			(at 25.699974 18.990056 180)
			(size 0.450088 0.450088)
			(layers "F.Cu" "F.Mask" "F.Paste")
			(net "M_F_CPU1_SB_DQ<5>")
		)
		(pad "CG67" smd circle
			(at 26.640028 18.990056 180)
			(size 0.450088 0.450088)
			(layers "F.Cu" "F.Mask" "F.Paste")
			(net "M_F_CPU1_SB_DQ<6>")
		)
		(pad "CG68" smd circle
			(at 27.580082 18.990056 180)
			(size 0.450088 0.450088)
			(layers "F.Cu" "F.Mask" "F.Paste")
			(net "GND")
		)
		(pad "CG69" smd circle
			(at 28.519882 18.990056 180)
			(size 0.450088 0.450088)
			(layers "F.Cu" "F.Mask" "F.Paste")
			(net "M_E_CPU1_SB_DQ<5>")
		)
		(pad "CG70" smd circle
			(at 29.459936 18.990056 180)
			(size 0.450088 0.450088)
			(layers "F.Cu" "F.Mask" "F.Paste")
			(net "GND")
		)
		(pad "CG71" smd circle
			(at 30.39999 18.990056 180)
			(size 0.450088 0.450088)
			(layers "F.Cu" "F.Mask" "F.Paste")
			(net "M_E_CPU1_SB_DQ<6>")
		)
		(pad "CG72" smd circle
			(at 31.340044 18.990056 180)
			(size 0.450088 0.450088)
			(layers "F.Cu" "F.Mask" "F.Paste")
			(net "PVDDIO_P1")
		)
		(pad "CG73" smd circle
			(at 32.280098 18.990056 180)
			(size 0.450088 0.450088)
			(layers "F.Cu" "F.Mask" "F.Paste")
			(net "M_A_CPU1_SB_DQ<5>")
		)
		(pad "CG74" smd circle
			(at 33.219898 18.990056 180)
			(size 0.450088 0.450088)
			(layers "F.Cu" "F.Mask" "F.Paste")
			(net "M_A_CPU1_SB_DQ<6>")
		)
		(pad "CG75" smd circle
			(at 34.159952 18.990056 180)
			(size 0.450088 0.450088)
			(layers "F.Cu" "F.Mask" "F.Paste")
			(net "GND")
		)
		(pad "CH2" smd circle
			(at -33.990026 19.800062 180)
			(size 0.450088 0.450088)
			(layers "F.Cu" "F.Mask" "F.Paste")
			(net "M_G_CPU1_SB_DQ<8>")
		)
		(pad "CH3" smd circle
			(at -33.049972 19.800062 180)
			(size 0.450088 0.450088)
			(layers "F.Cu" "F.Mask" "F.Paste")
			(net "GND")
		)
		(pad "CH4" smd circle
			(at -32.109918 19.800062 180)
			(size 0.450088 0.450088)
			(layers "F.Cu" "F.Mask" "F.Paste")
			(net "M_G_CPU1_SB_DQ<7>")
		)
		(pad "CH5" smd circle
			(at -31.170118 19.800062 180)
			(size 0.450088 0.450088)
			(layers "F.Cu" "F.Mask" "F.Paste")
			(net "GND")
		)
		(pad "CH6" smd circle
			(at -30.230064 19.800062 180)
			(size 0.450088 0.450088)
			(layers "F.Cu" "F.Mask" "F.Paste")
			(net "M_K_CPU1_SB_DQ<8>")
		)
		(pad "CH7" smd circle
			(at -29.29001 19.800062 180)
			(size 0.450088 0.450088)
			(layers "F.Cu" "F.Mask" "F.Paste")
			(net "M_K_CPU1_SB_DQ<7>")
		)
		(pad "CH8" smd circle
			(at -28.349956 19.800062 180)
			(size 0.450088 0.450088)
			(layers "F.Cu" "F.Mask" "F.Paste")
			(net "GND")
		)
		(pad "CH9" smd circle
			(at -27.409902 19.800062 180)
			(size 0.450088 0.450088)
			(layers "F.Cu" "F.Mask" "F.Paste")
			(net "M_L_CPU1_SB_DQ<8>")
		)
		(pad "CH10" smd circle
			(at -26.470102 19.800062 180)
			(size 0.450088 0.450088)
			(layers "F.Cu" "F.Mask" "F.Paste")
			(net "GND")
		)
		(pad "CH11" smd circle
			(at -25.530048 19.800062 180)
			(size 0.450088 0.450088)
			(layers "F.Cu" "F.Mask" "F.Paste")
			(net "M_L_CPU1_SB_DQ<7>")
		)
		(pad "CH12" smd circle
			(at -24.589994 19.800062 180)
			(size 0.450088 0.450088)
			(layers "F.Cu" "F.Mask" "F.Paste")
			(net "GND")
		)
		(pad "CH13" smd circle
			(at -23.64994 19.800062 180)
			(size 0.450088 0.450088)
			(layers "F.Cu" "F.Mask" "F.Paste")
			(net "M_H_CPU1_SB_DQ<8>")
		)
		(pad "CH14" smd circle
			(at -22.709886 19.800062 180)
			(size 0.450088 0.450088)
			(layers "F.Cu" "F.Mask" "F.Paste")
			(net "M_H_CPU1_SB_DQ<7>")
		)
		(pad "CH15" smd circle
			(at -21.770086 19.800062 180)
			(size 0.450088 0.450088)
			(layers "F.Cu" "F.Mask" "F.Paste")
			(net "GND")
		)
		(pad "CH16" smd circle
			(at -20.830032 19.800062 180)
			(size 0.450088 0.450088)
			(layers "F.Cu" "F.Mask" "F.Paste")
			(net "M_J_CPU1_SB_DQ<8>")
		)
		(pad "CH17" smd circle
			(at -19.889978 19.800062 180)
			(size 0.450088 0.450088)
			(layers "F.Cu" "F.Mask" "F.Paste")
			(net "GND")
		)
		(pad "CH18" smd circle
			(at -18.949924 19.800062 180)
			(size 0.450088 0.450088)
			(layers "F.Cu" "F.Mask" "F.Paste")
			(net "M_J_CPU1_SB_DQ<7>")
		)
		(pad "CH19" smd circle
			(at -18.010124 19.800062 180)
			(size 0.450088 0.450088)
			(layers "F.Cu" "F.Mask" "F.Paste")
			(net "GND")
		)
		(pad "CH20" smd circle
			(at -17.07007 19.800062 180)
			(size 0.450088 0.450088)
			(layers "F.Cu" "F.Mask" "F.Paste")
			(net "M_I_CPU1_SB_DQ<8>")
		)
		(pad "CH21" smd circle
			(at -16.130016 19.800062 180)
			(size 0.450088 0.450088)
			(layers "F.Cu" "F.Mask" "F.Paste")
			(net "M_I_CPU1_SB_DQ<7>")
		)
		(pad "CH22" smd circle
			(at -15.189962 19.800062 180)
			(size 0.450088 0.450088)
			(layers "F.Cu" "F.Mask" "F.Paste")
			(net "GND")
		)
		(pad "CH23" smd circle
			(at -14.249908 19.800062 180)
			(size 0.450088 0.450088)
			(layers "F.Cu" "F.Mask" "F.Paste")
			(net "PVDDCR_CPU1_P1")
		)
		(pad "CH24" smd circle
			(at -13.310108 19.800062 180)
			(size 0.450088 0.450088)
			(layers "F.Cu" "F.Mask" "F.Paste")
			(net "PVDDCR_CPU1_P1")
		)
		(pad "CH25" smd circle
			(at -12.370054 19.800062 180)
			(size 0.450088 0.450088)
			(layers "F.Cu" "F.Mask" "F.Paste")
			(net "GND")
		)
	)
)
